(kicad_pcb
	(version 20260206)
	(generator "pcbnew")
	(generator_version "10.0")
	(general
		(thickness 1.6)
		(legacy_teardrops no)
	)
	(paper "A4")
	(title_block
		(title "04192023_DAF0TMB3IC0_F0TG_MB_C_brd_V02_OCP.brd")
		(comment 1 "Grand Teton / footprints 148-155 of 8354")
	)
	(layers
		(0 "F.Cu" signal "TOP")
		(4 "In1.Cu" signal "GND")
		(6 "In2.Cu" signal "IN1")
		(8 "In3.Cu" signal "GND1")
		(10 "In4.Cu" signal "IN2")
		(12 "In5.Cu" signal "GND2")
		(14 "In6.Cu" signal "IN3")
		(16 "In7.Cu" signal "GND3")
		(18 "In8.Cu" signal "VCC")
		(20 "In9.Cu" signal "VCC1")
		(22 "In10.Cu" signal "GND4")
		(24 "In11.Cu" signal "IN4")
		(26 "In12.Cu" signal "GND5")
		(28 "In13.Cu" signal "IN5")
		(30 "In14.Cu" signal "GND6")
		(32 "In15.Cu" signal "IN6")
		(34 "In16.Cu" signal "GND7")
		(2 "B.Cu" signal "BOTTOM")
		(9 "F.Adhes" user "F.Adhesive")
		(11 "B.Adhes" user "B.Adhesive")
		(13 "F.Paste" user "Package Geometry/Pastemask Top")
		(15 "B.Paste" user "Package Geometry/Pastemask Bottom")
		(5 "F.SilkS" user "Ref Des/Silkscreen Top")
		(7 "B.SilkS" user "Ref Des/Silkscreen Bottom")
		(1 "F.Mask" user "Board Geometry/Soldermask Top")
		(3 "B.Mask" user "Board Geometry/Soldermask Bottom")
		(17 "Dwgs.User" user "User.Drawings")
		(19 "Cmts.User" user "User.Comments")
		(21 "Eco1.User" user "User.Eco1")
		(23 "Eco2.User" user "User.Eco2")
		(25 "Edge.Cuts" user "Board Geometry/Outline")
		(27 "Margin" user)
		(31 "F.CrtYd" user "Package Geometry/Place Bound Top")
		(29 "B.CrtYd" user "Package Geometry/Place Bound Bottom")
		(35 "F.Fab" user "Ref Des/Assembly Top")
		(33 "B.Fab" user "Ref Des/Assembly Bottom")
	)
	(footprint ""
		(layer "F.Cu")
		(at 358.389936 -393.47648 180)
		(property "Reference" "R1002"
			(at 0 0 180)
			(layer "F.SilkS")
			(hide yes)
			(effects
				(font
					(size 1.27 1.27)
				)
			)
		)
		(property "Value" ""
			(at 0 0 180)
			(layer "F.Fab")
			(effects
				(font
					(size 1.27 1.27)
				)
			)
		)
		(duplicate_pad_numbers_are_jumpers no)
		(fp_line
			(start 0.7874 0.4064)
			(end -0.7874 0.4064)
			(stroke
				(width 0.1524)
				(type default)
			)
			(layer "F.SilkS")
		)
		(fp_line
			(start 0.7874 -0.4064)
			(end 0.7874 0.4064)
			(stroke
				(width 0.1524)
				(type default)
			)
			(layer "F.SilkS")
		)
		(fp_line
			(start -0.7874 0.4064)
			(end -0.7874 -0.4064)
			(stroke
				(width 0.1524)
				(type default)
			)
			(layer "F.SilkS")
		)
		(fp_line
			(start -0.7874 -0.4064)
			(end 0.7874 -0.4064)
			(stroke
				(width 0.1524)
				(type default)
			)
			(layer "F.SilkS")
		)
		(fp_line
			(start 0.67945 0.3048)
			(end 0.120396 0.3048)
			(stroke
				(width 0.1)
				(type default)
			)
			(layer "F.Fab")
		)
		(fp_line
			(start 0.67945 -0.3048)
			(end 0.67945 0.3048)
			(stroke
				(width 0.1)
				(type default)
			)
			(layer "F.Fab")
		)
		(fp_line
			(start 0.12065 -0.2794)
			(end 0.12065 -0.3048)
			(stroke
				(width 0.1)
				(type default)
			)
			(layer "F.Fab")
		)
		(fp_line
			(start 0.12065 -0.3048)
			(end 0.67945 -0.3048)
			(stroke
				(width 0.1)
				(type default)
			)
			(layer "F.Fab")
		)
		(fp_line
			(start 0.120396 0.3048)
			(end 0.120396 0.2794)
			(stroke
				(width 0.1)
				(type default)
			)
			(layer "F.Fab")
		)
		(fp_line
			(start 0.120396 0.2794)
			(end -0.12065 0.2794)
			(stroke
				(width 0.1)
				(type default)
			)
			(layer "F.Fab")
		)
		(fp_line
			(start -0.12065 0.3048)
			(end -0.67945 0.3048)
			(stroke
				(width 0.1)
				(type default)
			)
			(layer "F.Fab")
		)
		(fp_line
			(start -0.12065 0.2794)
			(end -0.12065 0.3048)
			(stroke
				(width 0.1)
				(type default)
			)
			(layer "F.Fab")
		)
		(fp_line
			(start -0.12065 -0.2794)
			(end 0.12065 -0.2794)
			(stroke
				(width 0.1)
				(type default)
			)
			(layer "F.Fab")
		)
		(fp_line
			(start -0.12065 -0.305054)
			(end -0.12065 -0.2794)
			(stroke
				(width 0.1)
				(type default)
			)
			(layer "F.Fab")
		)
		(fp_line
			(start -0.67945 0.3048)
			(end -0.67945 -0.305054)
			(stroke
				(width 0.1)
				(type default)
			)
			(layer "F.Fab")
		)
		(fp_line
			(start -0.67945 -0.305054)
			(end -0.12065 -0.305054)
			(stroke
				(width 0.1)
				(type default)
			)
			(layer "F.Fab")
		)
		(pad "1" smd rect
			(at -0.40005 0)
			(size 0.4572 0.508)
			(layers "F.Cu" "F.Mask" "F.Paste")
			(net "P1V8_CPU0_RT1_1A_1D")
		)
		(pad "2" smd rect
			(at 0.40005 0)
			(size 0.4572 0.508)
			(layers "F.Cu" "F.Mask" "F.Paste")
			(net "P1V8_CPU0_RT1_1A")
		)
	)
	(footprint ""
		(layer "F.Cu")
		(at 452.115174 -413.0167 90)
		(property "Reference" "PL6504"
			(at -3.72237 -2.281174 0)
			(unlocked yes)
			(layer "F.SilkS")
			(effects
				(font
					(size 0.7874 0.5842)
					(thickness 0.1524)
				)
				(justify left)
			)
		)
		(property "Value" ""
			(at 0 0 90)
			(layer "F.Fab")
			(effects
				(font
					(size 1.27 1.27)
				)
			)
		)
		(duplicate_pad_numbers_are_jumpers no)
		(fp_line
			(start 2.249932 -2.249932)
			(end 2.249932 -1.3843)
			(stroke
				(width 0.1524)
				(type default)
			)
			(layer "F.SilkS")
		)
		(fp_line
			(start -2.249932 -2.249932)
			(end 2.249932 -2.249932)
			(stroke
				(width 0.1524)
				(type default)
			)
			(layer "F.SilkS")
		)
		(fp_line
			(start -2.249932 -1.3843)
			(end -2.249932 -2.249932)
			(stroke
				(width 0.1524)
				(type default)
			)
			(layer "F.SilkS")
		)
		(fp_line
			(start 2.249932 1.3843)
			(end 2.249932 2.249932)
			(stroke
				(width 0.1524)
				(type default)
			)
			(layer "F.SilkS")
		)
		(fp_line
			(start 2.249932 2.249932)
			(end -2.249932 2.249932)
			(stroke
				(width 0.1524)
				(type default)
			)
			(layer "F.SilkS")
		)
		(fp_line
			(start -2.249932 2.249932)
			(end -2.249932 1.3843)
			(stroke
				(width 0.1524)
				(type default)
			)
			(layer "F.SilkS")
		)
		(fp_line
			(start 2.249932 -2.249932)
			(end 2.249932 2.249932)
			(stroke
				(width 0.1)
				(type default)
			)
			(layer "F.Fab")
		)
		(fp_line
			(start -2.249932 -2.249932)
			(end 2.249932 -2.249932)
			(stroke
				(width 0.1)
				(type default)
			)
			(layer "F.Fab")
		)
		(fp_line
			(start 2.249932 2.249932)
			(end -2.249932 2.249932)
			(stroke
				(width 0.1)
				(type default)
			)
			(layer "F.Fab")
		)
		(fp_line
			(start -2.249932 2.249932)
			(end -2.249932 -2.249932)
			(stroke
				(width 0.1)
				(type default)
			)
			(layer "F.Fab")
		)
		(pad "1" smd rect
			(at -1.82499 0 90)
			(size 1.0668 2.5146)
			(layers "F.Cu" "F.Mask" "F.Paste")
			(net "SW_P12V_AUX_P0V9_RETIMER_CPU0_FLT")
		)
		(pad "2" smd rect
			(at 1.82499 0 90)
			(size 1.0668 2.5146)
			(layers "F.Cu" "F.Mask" "F.Paste")
			(net "P12V_AUX")
		)
	)
	(footprint ""
		(layer "F.Cu")
		(at 426.6692 -17.624298 90)
		(property "Reference" "C1574"
			(at 0 0 90)
			(layer "F.SilkS")
			(hide yes)
			(effects
				(font
					(size 1.27 1.27)
				)
			)
		)
		(property "Value" ""
			(at 0 0 90)
			(layer "F.Fab")
			(effects
				(font
					(size 1.27 1.27)
				)
			)
		)
		(duplicate_pad_numbers_are_jumpers no)
		(fp_line
			(start 0.299974 -0.150114)
			(end 0.299974 0.150114)
			(stroke
				(width 0.1)
				(type default)
			)
			(layer "F.Fab")
		)
		(fp_line
			(start -0.299974 -0.150114)
			(end 0.299974 -0.150114)
			(stroke
				(width 0.1)
				(type default)
			)
			(layer "F.Fab")
		)
		(fp_line
			(start 0.299974 0.150114)
			(end -0.299974 0.150114)
			(stroke
				(width 0.1)
				(type default)
			)
			(layer "F.Fab")
		)
		(fp_line
			(start -0.299974 0.150114)
			(end -0.299974 -0.150114)
			(stroke
				(width 0.1)
				(type default)
			)
			(layer "F.Fab")
		)
		(pad "1" smd rect
			(at -0.2667 0 90)
			(size 0.3048 0.381)
			(layers "F.Cu" "F.Mask" "F.Paste")
			(net "P5E_CPU0_G3_TX_C_DN<2>")
		)
		(pad "2" smd rect
			(at 0.2667 0 90)
			(size 0.3048 0.381)
			(layers "F.Cu" "F.Mask" "F.Paste")
			(net "P5E_CPU0_G3_TX_DN<2>")
		)
	)
	(footprint ""
		(layer "F.Cu")
		(at 440.333384 -16.014954 180)
		(property "Reference" "C1213"
			(at 0 0 180)
			(layer "F.SilkS")
			(hide yes)
			(effects
				(font
					(size 1.27 1.27)
				)
			)
		)
		(property "Value" ""
			(at 0 0 180)
			(layer "F.Fab")
			(effects
				(font
					(size 1.27 1.27)
				)
			)
		)
		(duplicate_pad_numbers_are_jumpers no)
		(fp_line
			(start 1.524 0.762)
			(end -1.524 0.762)
			(stroke
				(width 0.1524)
				(type default)
			)
			(layer "F.SilkS")
		)
		(fp_line
			(start 1.524 -0.762)
			(end 1.524 0.762)
			(stroke
				(width 0.1524)
				(type default)
			)
			(layer "F.SilkS")
		)
		(fp_line
			(start -1.524 0.762)
			(end -1.524 -0.762)
			(stroke
				(width 0.1524)
				(type default)
			)
			(layer "F.SilkS")
		)
		(fp_line
			(start -1.524 -0.762)
			(end 1.524 -0.762)
			(stroke
				(width 0.1524)
				(type default)
			)
			(layer "F.SilkS")
		)
		(fp_line
			(start 1.1049 0.724916)
			(end 1.1049 -0.724916)
			(stroke
				(width 0.1)
				(type default)
			)
			(layer "F.Fab")
		)
		(fp_line
			(start 1.1049 -0.724916)
			(end -1.1049 -0.724916)
			(stroke
				(width 0.1)
				(type default)
			)
			(layer "F.Fab")
		)
		(fp_line
			(start -1.1049 0.724916)
			(end 1.1049 0.724916)
			(stroke
				(width 0.1)
				(type default)
			)
			(layer "F.Fab")
		)
		(fp_line
			(start -1.1049 -0.724916)
			(end -1.1049 0.724916)
			(stroke
				(width 0.1)
				(type default)
			)
			(layer "F.Fab")
		)
		(pad "1" smd rect
			(at -0.889 0)
			(size 1.016 1.27)
			(layers "F.Cu" "F.Mask" "F.Paste")
			(net "P12V_OCP_SFF_R")
		)
		(pad "2" smd rect
			(at 0.889 0)
			(size 1.016 1.27)
			(layers "F.Cu" "F.Mask" "F.Paste")
			(net "GND")
		)
	)
	(footprint ""
		(layer "F.Cu")
		(at 398.473168 -45.272706 180)
		(property "Reference" ""
			(at 0 0 180)
			(layer "F.SilkS")
			(hide yes)
			(effects
				(font
					(size 1.27 1.27)
				)
			)
		)
		(property "Value" ""
			(at 0 0 180)
			(layer "F.Fab")
			(effects
				(font
					(size 1.27 1.27)
				)
			)
		)
		(duplicate_pad_numbers_are_jumpers no)
		(pad "1" smd circle
			(at 0 0 180)
			(size 0.9906 0.9906)
			(layers "F.Cu" "F.Mask" "F.Paste")
			(net "Net_2239")
		)
		(zone
			(layer "F.Cu")
			(hatch none 0.5)
			(connect_pads
				(clearance 0)
			)
			(min_thickness 0.25)
			(keepout
				(tracks not_allowed)
				(vias allowed)
				(pads allowed)
				(copperpour not_allowed)
				(footprints allowed)
			)
			(placement
				(enabled no)
				(sheetname "")
			)
			(fill
				(thermal_gap 0.5)
				(thermal_bridge_width 0.5)
				(island_removal_mode 0)
			)
			(polygon
				(pts
					(arc
						(start 400.098768 -45.272706)
						(mid 396.847568 -45.272706)
						(end 400.098768 -45.272706)
					)
				)
			)
		)
	)
	(footprint ""
		(layer "F.Cu")
		(at 359.716578 -166.830756 -90)
		(property "Reference" "PC567"
			(at 0 0 270)
			(layer "F.SilkS")
			(hide yes)
			(effects
				(font
					(size 1.27 1.27)
				)
			)
		)
		(property "Value" ""
			(at 0 0 270)
			(layer "F.Fab")
			(effects
				(font
					(size 1.27 1.27)
				)
			)
		)
		(duplicate_pad_numbers_are_jumpers no)
		(fp_line
			(start -0.7874 0.4064)
			(end -0.7874 -0.4064)
			(stroke
				(width 0.1524)
				(type default)
			)
			(layer "F.SilkS")
		)
		(fp_line
			(start -0.199644 0.4064)
			(end -0.7874 0.4064)
			(stroke
				(width 0.1524)
				(type default)
			)
			(layer "F.SilkS")
		)
		(fp_line
			(start 0.7874 0.4064)
			(end 0.409956 0.4064)
			(stroke
				(width 0.1524)
				(type default)
			)
			(layer "F.SilkS")
		)
		(fp_line
			(start -0.7874 -0.4064)
			(end 0.7874 -0.4064)
			(stroke
				(width 0.1524)
				(type default)
			)
			(layer "F.SilkS")
		)
		(fp_line
			(start 0.7874 -0.4064)
			(end 0.7874 0.4064)
			(stroke
				(width 0.1524)
				(type default)
			)
			(layer "F.SilkS")
		)
		(fp_line
			(start -0.67945 0.3048)
			(end -0.67945 -0.305054)
			(stroke
				(width 0.1)
				(type default)
			)
			(layer "F.Fab")
		)
		(fp_line
			(start -0.12065 0.3048)
			(end -0.67945 0.3048)
			(stroke
				(width 0.1)
				(type default)
			)
			(layer "F.Fab")
		)
		(fp_line
			(start 0.120396 0.3048)
			(end 0.120396 0.2794)
			(stroke
				(width 0.1)
				(type default)
			)
			(layer "F.Fab")
		)
		(fp_line
			(start 0.67945 0.3048)
			(end 0.120396 0.3048)
			(stroke
				(width 0.1)
				(type default)
			)
			(layer "F.Fab")
		)
		(fp_line
			(start -0.12065 0.2794)
			(end -0.12065 0.3048)
			(stroke
				(width 0.1)
				(type default)
			)
			(layer "F.Fab")
		)
		(fp_line
			(start 0.120396 0.2794)
			(end -0.12065 0.2794)
			(stroke
				(width 0.1)
				(type default)
			)
			(layer "F.Fab")
		)
		(fp_line
			(start -0.12065 -0.2794)
			(end 0.12065 -0.2794)
			(stroke
				(width 0.1)
				(type default)
			)
			(layer "F.Fab")
		)
		(fp_line
			(start 0.12065 -0.2794)
			(end 0.12065 -0.3048)
			(stroke
				(width 0.1)
				(type default)
			)
			(layer "F.Fab")
		)
		(fp_line
			(start 0.12065 -0.3048)
			(end 0.67945 -0.3048)
			(stroke
				(width 0.1)
				(type default)
			)
			(layer "F.Fab")
		)
		(fp_line
			(start 0.67945 -0.3048)
			(end 0.67945 0.3048)
			(stroke
				(width 0.1)
				(type default)
			)
			(layer "F.Fab")
		)
		(fp_line
			(start -0.67945 -0.305054)
			(end -0.12065 -0.305054)
			(stroke
				(width 0.1)
				(type default)
			)
			(layer "F.Fab")
		)
		(fp_line
			(start -0.12065 -0.305054)
			(end -0.12065 -0.2794)
			(stroke
				(width 0.1)
				(type default)
			)
			(layer "F.Fab")
		)
		(pad "1" smd circle
			(at -0.40005 0 270)
			(size 0 0)
			(layers "F.Cu" "F.Mask" "F.Paste")
			(net "PVDDCR_CPU0_P0_VCC5")
		)
		(pad "2" smd circle
			(at 0.40005 0 270)
			(size 0 0)
			(layers "F.Cu" "F.Mask" "F.Paste")
			(net "GND")
		)
	)
	(footprint ""
		(layer "F.Cu")
		(at 424.403266 -355.718364 90)
		(property "Reference" "PR135"
			(at 0 0 90)
			(layer "F.SilkS")
			(hide yes)
			(effects
				(font
					(size 1.27 1.27)
				)
			)
		)
		(property "Value" ""
			(at 0 0 90)
			(layer "F.Fab")
			(effects
				(font
					(size 1.27 1.27)
				)
			)
		)
		(duplicate_pad_numbers_are_jumpers no)
		(fp_line
			(start 0.7874 -0.4064)
			(end 0.7874 0.4064)
			(stroke
				(width 0.1524)
				(type default)
			)
			(layer "F.SilkS")
		)
		(fp_line
			(start -0.7874 -0.4064)
			(end 0.7874 -0.4064)
			(stroke
				(width 0.1524)
				(type default)
			)
			(layer "F.SilkS")
		)
		(fp_line
			(start 0.7874 0.4064)
			(end -0.7874 0.4064)
			(stroke
				(width 0.1524)
				(type default)
			)
			(layer "F.SilkS")
		)
		(fp_line
			(start -0.7874 0.4064)
			(end -0.7874 -0.4064)
			(stroke
				(width 0.1524)
				(type default)
			)
			(layer "F.SilkS")
		)
		(fp_line
			(start -0.12065 -0.305054)
			(end -0.12065 -0.2794)
			(stroke
				(width 0.1)
				(type default)
			)
			(layer "F.Fab")
		)
		(fp_line
			(start -0.67945 -0.305054)
			(end -0.12065 -0.305054)
			(stroke
				(width 0.1)
				(type default)
			)
			(layer "F.Fab")
		)
		(fp_line
			(start 0.67945 -0.3048)
			(end 0.67945 0.3048)
			(stroke
				(width 0.1)
				(type default)
			)
			(layer "F.Fab")
		)
		(fp_line
			(start 0.12065 -0.3048)
			(end 0.67945 -0.3048)
			(stroke
				(width 0.1)
				(type default)
			)
			(layer "F.Fab")
		)
		(fp_line
			(start 0.12065 -0.2794)
			(end 0.12065 -0.3048)
			(stroke
				(width 0.1)
				(type default)
			)
			(layer "F.Fab")
		)
		(fp_line
			(start -0.12065 -0.2794)
			(end 0.12065 -0.2794)
			(stroke
				(width 0.1)
				(type default)
			)
			(layer "F.Fab")
		)
		(fp_line
			(start 0.120396 0.2794)
			(end -0.12065 0.2794)
			(stroke
				(width 0.1)
				(type default)
			)
			(layer "F.Fab")
		)
		(fp_line
			(start -0.12065 0.2794)
			(end -0.12065 0.3048)
			(stroke
				(width 0.1)
				(type default)
			)
			(layer "F.Fab")
		)
		(fp_line
			(start 0.67945 0.3048)
			(end 0.120396 0.3048)
			(stroke
				(width 0.1)
				(type default)
			)
			(layer "F.Fab")
		)
		(fp_line
			(start 0.120396 0.3048)
			(end 0.120396 0.2794)
			(stroke
				(width 0.1)
				(type default)
			)
			(layer "F.Fab")
		)
		(fp_line
			(start -0.12065 0.3048)
			(end -0.67945 0.3048)
			(stroke
				(width 0.1)
				(type default)
			)
			(layer "F.Fab")
		)
		(fp_line
			(start -0.67945 0.3048)
			(end -0.67945 -0.305054)
			(stroke
				(width 0.1)
				(type default)
			)
			(layer "F.Fab")
		)
		(pad "1" smd circle
			(at -0.40005 0 90)
			(size 0 0)
			(layers "F.Cu" "F.Mask" "F.Paste")
			(net "SW_PVDD11_S3_P0_BOOT1")
		)
		(pad "2" smd circle
			(at 0.40005 0 90)
			(size 0 0)
			(layers "F.Cu" "F.Mask" "F.Paste")
			(net "SW_PVDD11_S3_P0_BOOT1_RC")
		)
	)
	(footprint ""
		(layer "F.Cu")
		(at 35.881818 -436.433214)
		(property "Reference" "R2990"
			(at 0 0 0)
			(layer "F.SilkS")
			(hide yes)
			(effects
				(font
					(size 1.27 1.27)
				)
			)
		)
		(property "Value" ""
			(at 0 0 0)
			(layer "F.Fab")
			(effects
				(font
					(size 1.27 1.27)
				)
			)
		)
		(duplicate_pad_numbers_are_jumpers no)
		(fp_line
			(start -0.7874 -0.4064)
			(end 0.7874 -0.4064)
			(stroke
				(width 0.1524)
				(type default)
			)
			(layer "F.SilkS")
		)
		(fp_line
			(start -0.7874 0.4064)
			(end -0.7874 -0.4064)
			(stroke
				(width 0.1524)
				(type default)
			)
			(layer "F.SilkS")
		)
		(fp_line
			(start 0.7874 -0.4064)
			(end 0.7874 0.4064)
			(stroke
				(width 0.1524)
				(type default)
			)
			(layer "F.SilkS")
		)
		(fp_line
			(start 0.7874 0.4064)
			(end -0.7874 0.4064)
			(stroke
				(width 0.1524)
				(type default)
			)
			(layer "F.SilkS")
		)
		(fp_line
			(start -0.67945 -0.305054)
			(end -0.12065 -0.305054)
			(stroke
				(width 0.1)
				(type default)
			)
			(layer "F.Fab")
		)
		(fp_line
			(start -0.67945 0.3048)
			(end -0.67945 -0.305054)
			(stroke
				(width 0.1)
				(type default)
			)
			(layer "F.Fab")
		)
		(fp_line
			(start -0.12065 -0.305054)
			(end -0.12065 -0.2794)
			(stroke
				(width 0.1)
				(type default)
			)
			(layer "F.Fab")
		)
		(fp_line
			(start -0.12065 -0.2794)
			(end 0.12065 -0.2794)
			(stroke
				(width 0.1)
				(type default)
			)
			(layer "F.Fab")
		)
		(fp_line
			(start -0.12065 0.2794)
			(end -0.12065 0.3048)
			(stroke
				(width 0.1)
				(type default)
			)
			(layer "F.Fab")
		)
		(fp_line
			(start -0.12065 0.3048)
			(end -0.67945 0.3048)
			(stroke
				(width 0.1)
				(type default)
			)
			(layer "F.Fab")
		)
		(fp_line
			(start 0.120396 0.2794)
			(end -0.12065 0.2794)
			(stroke
				(width 0.1)
				(type default)
			)
			(layer "F.Fab")
		)
		(fp_line
			(start 0.120396 0.3048)
			(end 0.120396 0.2794)
			(stroke
				(width 0.1)
				(type default)
			)
			(layer "F.Fab")
		)
		(fp_line
			(start 0.12065 -0.3048)
			(end 0.67945 -0.3048)
			(stroke
				(width 0.1)
				(type default)
			)
			(layer "F.Fab")
		)
		(fp_line
			(start 0.12065 -0.2794)
			(end 0.12065 -0.3048)
			(stroke
				(width 0.1)
				(type default)
			)
			(layer "F.Fab")
		)
		(fp_line
			(start 0.67945 -0.3048)
			(end 0.67945 0.3048)
			(stroke
				(width 0.1)
				(type default)
			)
			(layer "F.Fab")
		)
		(fp_line
			(start 0.67945 0.3048)
			(end 0.120396 0.3048)
			(stroke
				(width 0.1)
				(type default)
			)
			(layer "F.Fab")
		)
		(pad "1" smd circle
			(at -0.40005 0)
			(size 0 0)
			(layers "F.Cu" "F.Mask" "F.Paste")
			(net "SMB_2_BMC_GPU_BUF_R_SCL")
		)
		(pad "2" smd circle
			(at 0.40005 0)
			(size 0 0)
			(layers "F.Cu" "F.Mask" "F.Paste")
			(net "SMB_2_BMC_GPU_BUF_SCL")
		)
	)
)
